(kicad_pcb
	(version 20260206)
	(generator "pcbnew")
	(generator_version "10.0")
	(general
		(thickness 1.6)
		(legacy_teardrops no)
	)
	(paper "A4")
	(title_block
		(title "Wiwynn_Tioga_Pass_MB.brd")
		(comment 1 "Tioga Pass / footprints 3010-3017 of 4770")
	)
	(layers
		(0 "F.Cu" signal "TOP")
		(4 "In1.Cu" signal "L2GND")
		(6 "In2.Cu" signal "L3")
		(8 "In3.Cu" signal "L4GND")
		(10 "In4.Cu" signal "L5")
		(12 "In5.Cu" signal "L6GND")
		(14 "In6.Cu" signal "L7VCC")
		(16 "In7.Cu" signal "L8VCC")
		(18 "In8.Cu" signal "L9GND")
		(20 "In9.Cu" signal "L10")
		(22 "In10.Cu" signal "L11GND")
		(24 "In11.Cu" signal "L12")
		(26 "In12.Cu" signal "L13GND")
		(2 "B.Cu" signal "BOTTOM")
		(9 "F.Adhes" user "F.Adhesive")
		(11 "B.Adhes" user "B.Adhesive")
		(13 "F.Paste" user "Package Geometry/Pastemask Top")
		(15 "B.Paste" user "Package Geometry/Pastemask Bottom")
		(5 "F.SilkS" user "Ref Des/Silkscreen Top")
		(7 "B.SilkS" user "Ref Des/Silkscreen Bottom")
		(1 "F.Mask" user "Board Geometry/Soldermask Top")
		(3 "B.Mask" user "Board Geometry/Soldermask Bottom")
		(17 "Dwgs.User" user "User.Drawings")
		(19 "Cmts.User" user "User.Comments")
		(21 "Eco1.User" user "User.Eco1")
		(23 "Eco2.User" user "User.Eco2")
		(25 "Edge.Cuts" user "Board Geometry/Outline")
		(27 "Margin" user)
		(31 "F.CrtYd" user "Package Geometry/Place Bound Top")
		(29 "B.CrtYd" user "Package Geometry/Place Bound Bottom")
		(35 "F.Fab" user "Ref Des/Assembly Top")
		(33 "B.Fab" user "Ref Des/Assembly Bottom")
	)
	(footprint ""
		(layer "B.Cu")
		(at 318.9732 -33.1978 -90)
		(property "Reference" "R4T2"
			(at 0 0 90)
			(layer "B.SilkS")
			(hide yes)
			(effects
				(font
					(size 1.27 1.27)
				)
				(justify mirror)
			)
		)
		(property "Value" ""
			(at 0 0 90)
			(layer "B.Fab")
			(effects
				(font
					(size 1.27 1.27)
				)
				(justify mirror)
			)
		)
		(duplicate_pad_numbers_are_jumpers no)
		(fp_poly
			(pts
				(xy 0.2794 -0.1016) (xy -0.2794 -0.1016) (xy -0.2794 0.9906) (xy 0.2794 0.9906)
			)
			(stroke
				(width 0)
				(type default)
			)
			(fill no)
			(layer "B.CrtYd")
		)
		(fp_line
			(start -0.2794 0.9906)
			(end -0.2794 -0.1016)
			(stroke
				(width 0.1)
				(type default)
			)
			(layer "B.Fab")
		)
		(fp_line
			(start 0.2794 0.9906)
			(end -0.2794 0.9906)
			(stroke
				(width 0.1)
				(type default)
			)
			(layer "B.Fab")
		)
		(fp_line
			(start -0.2794 -0.1016)
			(end 0.2794 -0.1016)
			(stroke
				(width 0.1)
				(type default)
			)
			(layer "B.Fab")
		)
		(fp_line
			(start 0.2794 -0.1016)
			(end 0.2794 0.9906)
			(stroke
				(width 0.1)
				(type default)
			)
			(layer "B.Fab")
		)
		(pad "1" smd rect
			(at 0 0 90)
			(size 0.508 0.508)
			(layers "B.Cu" "B.Mask" "B.Paste")
			(net "FM_ADR_COMPLETE")
		)
		(pad "2" smd rect
			(at 0 0.889 90)
			(size 0.508 0.508)
			(layers "B.Cu" "B.Mask" "B.Paste")
			(net "FM_ADR_COMPLETE_R")
		)
		(zone
			(layer "B.Cu")
			(hatch none 0.5)
			(connect_pads
				(clearance 0)
			)
			(min_thickness 0.25)
			(keepout
				(tracks not_allowed)
				(vias allowed)
				(pads allowed)
				(copperpour not_allowed)
				(footprints allowed)
			)
			(placement
				(enabled no)
				(sheetname "")
			)
			(fill
				(thermal_gap 0.5)
				(thermal_bridge_width 0.5)
				(island_removal_mode 0)
			)
			(polygon
				(pts
					(xy 318.3382 -32.9438) (xy 318.3382 -33.4518) (xy 318.7192 -33.4518) (xy 318.7192 -32.9438)
				)
			)
		)
		(zone
			(layer "B.Cu")
			(hatch none 0.5)
			(connect_pads
				(clearance 0)
			)
			(min_thickness 0.25)
			(keepout
				(tracks allowed)
				(vias not_allowed)
				(pads allowed)
				(copperpour not_allowed)
				(footprints allowed)
			)
			(placement
				(enabled no)
				(sheetname "")
			)
			(fill
				(thermal_gap 0.5)
				(thermal_bridge_width 0.5)
				(island_removal_mode 0)
			)
			(polygon
				(pts
					(xy 318.7192 -32.9438) (xy 318.7192 -33.4518) (xy 318.3382 -33.4518) (xy 318.3382 -32.9438)
				)
			)
		)
	)
	(footprint ""
		(layer "B.Cu")
		(at 386.503672 -154.721306)
		(property "Reference" "C3L9"
			(at 0 0 0)
			(layer "B.SilkS")
			(hide yes)
			(effects
				(font
					(size 1.27 1.27)
				)
				(justify mirror)
			)
		)
		(property "Value" ""
			(at 0 0 0)
			(layer "B.Fab")
			(effects
				(font
					(size 1.27 1.27)
				)
				(justify mirror)
			)
		)
		(duplicate_pad_numbers_are_jumpers no)
		(fp_poly
			(pts
				(xy 0.7239 -0.2159) (xy -0.7239 -0.2159) (xy -0.7239 1.9939) (xy 0.7239 1.9939)
			)
			(stroke
				(width 0)
				(type default)
			)
			(fill no)
			(layer "B.CrtYd")
		)
		(fp_line
			(start -0.7239 -0.2159)
			(end 0.7239 -0.2159)
			(stroke
				(width 0.1)
				(type default)
			)
			(layer "B.Fab")
		)
		(fp_line
			(start -0.7239 1.9939)
			(end -0.7239 -0.2159)
			(stroke
				(width 0.1)
				(type default)
			)
			(layer "B.Fab")
		)
		(fp_line
			(start 0.7239 -0.2159)
			(end 0.7239 1.9939)
			(stroke
				(width 0.1)
				(type default)
			)
			(layer "B.Fab")
		)
		(fp_line
			(start 0.7239 1.9939)
			(end -0.7239 1.9939)
			(stroke
				(width 0.1)
				(type default)
			)
			(layer "B.Fab")
		)
		(pad "1" smd rect
			(at 0 0 180)
			(size 1.27 1.016)
			(layers "B.Cu" "B.Mask" "B.Paste")
			(net "VR_FET_SW_P12V_STBY_PVDDQ_DEF")
		)
		(pad "2" smd rect
			(at 0 1.778 180)
			(size 1.27 1.016)
			(layers "B.Cu" "B.Mask" "B.Paste")
			(net "GND")
		)
		(zone
			(layer "B.Cu")
			(hatch none 0.5)
			(connect_pads
				(clearance 0)
			)
			(min_thickness 0.25)
			(keepout
				(tracks not_allowed)
				(vias allowed)
				(pads allowed)
				(copperpour not_allowed)
				(footprints allowed)
			)
			(placement
				(enabled no)
				(sheetname "")
			)
			(fill
				(thermal_gap 0.5)
				(thermal_bridge_width 0.5)
				(island_removal_mode 0)
			)
			(polygon
				(pts
					(xy 387.138672 -154.213306) (xy 385.868672 -154.213306) (xy 385.868672 -153.451306) (xy 387.138672 -153.451306)
				)
			)
		)
	)
	(footprint ""
		(layer "B.Cu")
		(at 350.52 -104.267 180)
		(property "Reference" "C22W32"
			(at 0 0 0)
			(layer "B.SilkS")
			(hide yes)
			(effects
				(font
					(size 1.27 1.27)
				)
				(justify mirror)
			)
		)
		(property "Value" "*"
			(at 0.0762 -6.2357 180)
			(unlocked yes)
			(layer "B.Fab")
			(hide yes)
			(effects
				(font
					(size 1.27 1.016)
					(thickness 0.1524)
				)
				(justify mirror)
			)
		)
		(property "Device Type" "SC22U16V5MX-4-GP_SMD-BCG5-SC22A"
			(at 0.0762 -8.2677 180)
			(unlocked yes)
			(layer "B.Fab")
			(hide yes)
			(effects
				(font
					(size 1.27 1.016)
					(thickness 0.1524)
				)
				(justify mirror)
			)
		)
		(duplicate_pad_numbers_are_jumpers no)
		(fp_line
			(start -0.635 0)
			(end 0.635 0)
			(stroke
				(width 0.508)
				(type default)
			)
			(layer "B.SilkS")
		)
		(fp_rect
			(start 0.9652 1.778)
			(end -0.9652 -1.778)
			(stroke
				(width 0)
				(type default)
			)
			(fill no)
			(layer "B.CrtYd")
		)
		(fp_poly
			(pts
				(xy 0.9652 -1.778) (xy -0.9652 -1.778) (xy -0.9652 1.778) (xy 0.9652 1.778)
			)
			(stroke
				(width 0)
				(type default)
			)
			(fill no)
			(layer "B.Fab")
		)
		(pad "1" smd rect
			(at 0 -0.9652)
			(size 1.397 1.143)
			(layers "B.Cu" "B.Mask" "B.Paste")
			(net "VR_FET_SW_P12V_STBY_PVCCIO_CPU0")
		)
		(pad "2" smd rect
			(at 0 0.9652)
			(size 1.397 1.143)
			(layers "B.Cu" "B.Mask" "B.Paste")
			(net "GND")
		)
	)
	(footprint ""
		(layer "B.Cu")
		(at 401.5613 -39.5224 90)
		(property "Reference" "R2U5"
			(at 0 0 90)
			(layer "B.SilkS")
			(hide yes)
			(effects
				(font
					(size 1.27 1.27)
				)
				(justify mirror)
			)
		)
		(property "Value" ""
			(at 0 0 90)
			(layer "B.Fab")
			(effects
				(font
					(size 1.27 1.27)
				)
				(justify mirror)
			)
		)
		(duplicate_pad_numbers_are_jumpers no)
		(fp_poly
			(pts
				(xy 0.2794 -0.1016) (xy -0.2794 -0.1016) (xy -0.2794 0.9906) (xy 0.2794 0.9906)
			)
			(stroke
				(width 0)
				(type default)
			)
			(fill no)
			(layer "B.CrtYd")
		)
		(fp_line
			(start 0.2794 -0.1016)
			(end 0.2794 0.9906)
			(stroke
				(width 0.1)
				(type default)
			)
			(layer "B.Fab")
		)
		(fp_line
			(start -0.2794 -0.1016)
			(end 0.2794 -0.1016)
			(stroke
				(width 0.1)
				(type default)
			)
			(layer "B.Fab")
		)
		(fp_line
			(start 0.2794 0.9906)
			(end -0.2794 0.9906)
			(stroke
				(width 0.1)
				(type default)
			)
			(layer "B.Fab")
		)
		(fp_line
			(start -0.2794 0.9906)
			(end -0.2794 -0.1016)
			(stroke
				(width 0.1)
				(type default)
			)
			(layer "B.Fab")
		)
		(pad "1" smd rect
			(at 0 0 270)
			(size 0.508 0.508)
			(layers "B.Cu" "B.Mask" "B.Paste")
			(net "P3V3_STBY")
		)
		(pad "2" smd rect
			(at 0 0.889 270)
			(size 0.508 0.508)
			(layers "B.Cu" "B.Mask" "B.Paste")
			(net "SMB_OCP_FRU_STBY_LVC3_SCL_R")
		)
		(zone
			(layer "B.Cu")
			(hatch none 0.5)
			(connect_pads
				(clearance 0)
			)
			(min_thickness 0.25)
			(keepout
				(tracks allowed)
				(vias not_allowed)
				(pads allowed)
				(copperpour not_allowed)
				(footprints allowed)
			)
			(placement
				(enabled no)
				(sheetname "")
			)
			(fill
				(thermal_gap 0.5)
				(thermal_bridge_width 0.5)
				(island_removal_mode 0)
			)
			(polygon
				(pts
					(xy 401.8153 -39.7764) (xy 401.8153 -39.2684) (xy 402.1963 -39.2684) (xy 402.1963 -39.7764)
				)
			)
		)
		(zone
			(layer "B.Cu")
			(hatch none 0.5)
			(connect_pads
				(clearance 0)
			)
			(min_thickness 0.25)
			(keepout
				(tracks not_allowed)
				(vias allowed)
				(pads allowed)
				(copperpour not_allowed)
				(footprints allowed)
			)
			(placement
				(enabled no)
				(sheetname "")
			)
			(fill
				(thermal_gap 0.5)
				(thermal_bridge_width 0.5)
				(island_removal_mode 0)
			)
			(polygon
				(pts
					(xy 402.1963 -39.7764) (xy 402.1963 -39.2684) (xy 401.8153 -39.2684) (xy 401.8153 -39.7764)
				)
			)
		)
	)
	(footprint ""
		(layer "B.Cu")
		(at 390.93775 -105.45445)
		(property "Reference" "C2N18"
			(at 0 0 0)
			(layer "B.SilkS")
			(hide yes)
			(effects
				(font
					(size 1.27 1.27)
				)
				(justify mirror)
			)
		)
		(property "Value" ""
			(at 0 0 0)
			(layer "B.Fab")
			(effects
				(font
					(size 1.27 1.27)
				)
				(justify mirror)
			)
		)
		(duplicate_pad_numbers_are_jumpers no)
		(fp_rect
			(start 0.2794 0.9144)
			(end -0.2794 -0.1143)
			(stroke
				(width 0)
				(type default)
			)
			(fill no)
			(layer "B.CrtYd")
		)
		(fp_line
			(start -0.2794 -0.1143)
			(end -0.2794 0.9144)
			(stroke
				(width 0.1)
				(type default)
			)
			(layer "B.Fab")
		)
		(fp_line
			(start -0.2794 0.9144)
			(end 0.2794 0.9144)
			(stroke
				(width 0.1)
				(type default)
			)
			(layer "B.Fab")
		)
		(fp_line
			(start 0.2794 -0.1143)
			(end -0.2794 -0.1143)
			(stroke
				(width 0.1)
				(type default)
			)
			(layer "B.Fab")
		)
		(fp_line
			(start 0.2794 0.9144)
			(end 0.2794 -0.1143)
			(stroke
				(width 0.1)
				(type default)
			)
			(layer "B.Fab")
		)
		(pad "1" smd custom
			(at 0 0 270)
			(size 0.10414 0.10414)
			(layers "B.Cu" "B.Mask" "B.Paste")
			(net "P3V3_STBY")
			(options
				(clearance outline)
				(anchor circle)
			)
			(primitives
				(gr_poly
					(pts
						(xy -0.20828 -0.08636) (xy -0.20828 0.08636) (xy -0.08636 0.20828) (xy 0.086614 0.20828) (xy 0.20828 0.086614)
						(xy 0.20828 -0.08636) (xy 0.08636 -0.20828) (xy -0.08636 -0.20828)
					)
					(width 0)
					(fill yes)
				)
			)
		)
		(pad "2" smd custom
			(at 0 0.8001 270)
			(size 0.10414 0.10414)
			(layers "B.Cu" "B.Mask" "B.Paste")
			(net "GND")
			(options
				(clearance outline)
				(anchor circle)
			)
			(primitives
				(gr_poly
					(pts
						(xy -0.20828 -0.08636) (xy -0.20828 0.08636) (xy -0.08636 0.20828) (xy 0.086614 0.20828) (xy 0.20828 0.086614)
						(xy 0.20828 -0.08636) (xy 0.08636 -0.20828) (xy -0.08636 -0.20828)
					)
					(width 0)
					(fill yes)
				)
			)
		)
		(zone
			(layer "B.Cu")
			(hatch none 0.5)
			(connect_pads
				(clearance 0)
			)
			(min_thickness 0.25)
			(keepout
				(tracks not_allowed)
				(vias allowed)
				(pads allowed)
				(copperpour not_allowed)
				(footprints allowed)
			)
			(placement
				(enabled no)
				(sheetname "")
			)
			(fill
				(thermal_gap 0.5)
				(thermal_bridge_width 0.5)
				(island_removal_mode 0)
			)
			(polygon
				(pts
					(xy 391.02538 -105.2449) (xy 391.02538 -104.8639) (xy 390.85012 -104.8639) (xy 390.849866 -105.2449)
				)
			)
		)
		(zone
			(layer "B.Cu")
			(hatch none 0.5)
			(connect_pads
				(clearance 0)
			)
			(min_thickness 0.25)
			(keepout
				(tracks allowed)
				(vias not_allowed)
				(pads allowed)
				(copperpour not_allowed)
				(footprints allowed)
			)
			(placement
				(enabled no)
				(sheetname "")
			)
			(fill
				(thermal_gap 0.5)
				(thermal_bridge_width 0.5)
				(island_removal_mode 0)
			)
			(polygon
				(pts
					(xy 391.02538 -105.2449) (xy 391.02538 -104.8639) (xy 390.85012 -104.8639) (xy 390.849866 -105.2449)
				)
			)
		)
	)
	(footprint ""
		(layer "B.Cu")
		(at 401.108418 -26.471372 180)
		(property "Reference" "R1U32"
			(at 0 0 0)
			(layer "B.SilkS")
			(hide yes)
			(effects
				(font
					(size 1.27 1.27)
				)
				(justify mirror)
			)
		)
		(property "Value" ""
			(at 0 0 0)
			(layer "B.Fab")
			(effects
				(font
					(size 1.27 1.27)
				)
				(justify mirror)
			)
		)
		(duplicate_pad_numbers_are_jumpers no)
		(fp_poly
			(pts
				(xy 0.2794 -0.1016) (xy -0.2794 -0.1016) (xy -0.2794 0.9906) (xy 0.2794 0.9906)
			)
			(stroke
				(width 0)
				(type default)
			)
			(fill no)
			(layer "B.CrtYd")
		)
		(fp_line
			(start 0.2794 0.9906)
			(end -0.2794 0.9906)
			(stroke
				(width 0.1)
				(type default)
			)
			(layer "B.Fab")
		)
		(fp_line
			(start 0.2794 -0.1016)
			(end 0.2794 0.9906)
			(stroke
				(width 0.1)
				(type default)
			)
			(layer "B.Fab")
		)
		(fp_line
			(start -0.2794 0.9906)
			(end -0.2794 -0.1016)
			(stroke
				(width 0.1)
				(type default)
			)
			(layer "B.Fab")
		)
		(fp_line
			(start -0.2794 -0.1016)
			(end 0.2794 -0.1016)
			(stroke
				(width 0.1)
				(type default)
			)
			(layer "B.Fab")
		)
		(pad "1" smd rect
			(at 0 0)
			(size 0.508 0.508)
			(layers "B.Cu" "B.Mask" "B.Paste")
			(net "P12V_STBY")
		)
		(pad "2" smd rect
			(at 0 0.889)
			(size 0.508 0.508)
			(layers "B.Cu" "B.Mask" "B.Paste")
			(net "A_P12V_STBY_SCALED")
		)
		(zone
			(layer "B.Cu")
			(hatch none 0.5)
			(connect_pads
				(clearance 0)
			)
			(min_thickness 0.25)
			(keepout
				(tracks not_allowed)
				(vias allowed)
				(pads allowed)
				(copperpour not_allowed)
				(footprints allowed)
			)
			(placement
				(enabled no)
				(sheetname "")
			)
			(fill
				(thermal_gap 0.5)
				(thermal_bridge_width 0.5)
				(island_removal_mode 0)
			)
			(polygon
				(pts
					(xy 400.854418 -27.106372) (xy 401.362418 -27.106372) (xy 401.362418 -26.725372) (xy 400.854418 -26.725372)
				)
			)
		)
		(zone
			(layer "B.Cu")
			(hatch none 0.5)
			(connect_pads
				(clearance 0)
			)
			(min_thickness 0.25)
			(keepout
				(tracks allowed)
				(vias not_allowed)
				(pads allowed)
				(copperpour not_allowed)
				(footprints allowed)
			)
			(placement
				(enabled no)
				(sheetname "")
			)
			(fill
				(thermal_gap 0.5)
				(thermal_bridge_width 0.5)
				(island_removal_mode 0)
			)
			(polygon
				(pts
					(xy 400.854418 -26.725372) (xy 401.362418 -26.725372) (xy 401.362418 -27.106372) (xy 400.854418 -27.106372)
				)
			)
		)
	)
	(footprint ""
		(layer "B.Cu")
		(at 384.289808 -84.729828 180)
		(property "Reference" "R3P53"
			(at 0 0 0)
			(layer "B.SilkS")
			(hide yes)
			(effects
				(font
					(size 1.27 1.27)
				)
				(justify mirror)
			)
		)
		(property "Value" ""
			(at 0 0 0)
			(layer "B.Fab")
			(effects
				(font
					(size 1.27 1.27)
				)
				(justify mirror)
			)
		)
		(duplicate_pad_numbers_are_jumpers no)
		(fp_poly
			(pts
				(xy 0.2794 -0.1016) (xy -0.2794 -0.1016) (xy -0.2794 0.9906) (xy 0.2794 0.9906)
			)
			(stroke
				(width 0)
				(type default)
			)
			(fill no)
			(layer "B.CrtYd")
		)
		(fp_line
			(start 0.2794 0.9906)
			(end -0.2794 0.9906)
			(stroke
				(width 0.1)
				(type default)
			)
			(layer "B.Fab")
		)
		(fp_line
			(start 0.2794 -0.1016)
			(end 0.2794 0.9906)
			(stroke
				(width 0.1)
				(type default)
			)
			(layer "B.Fab")
		)
		(fp_line
			(start -0.2794 0.9906)
			(end -0.2794 -0.1016)
			(stroke
				(width 0.1)
				(type default)
			)
			(layer "B.Fab")
		)
		(fp_line
			(start -0.2794 -0.1016)
			(end 0.2794 -0.1016)
			(stroke
				(width 0.1)
				(type default)
			)
			(layer "B.Fab")
		)
		(pad "1" smd rect
			(at 0 0)
			(size 0.508 0.508)
			(layers "B.Cu" "B.Mask" "B.Paste")
			(net "P1V05_PCH_STBY")
		)
		(pad "2" smd rect
			(at 0 0.889)
			(size 0.508 0.508)
			(layers "B.Cu" "B.Mask" "B.Paste")
			(net "FM_OCP_MEZZC_PRES_1V05_PCH_N")
		)
		(zone
			(layer "B.Cu")
			(hatch none 0.5)
			(connect_pads
				(clearance 0)
			)
			(min_thickness 0.25)
			(keepout
				(tracks not_allowed)
				(vias allowed)
				(pads allowed)
				(copperpour not_allowed)
				(footprints allowed)
			)
			(placement
				(enabled no)
				(sheetname "")
			)
			(fill
				(thermal_gap 0.5)
				(thermal_bridge_width 0.5)
				(island_removal_mode 0)
			)
			(polygon
				(pts
					(xy 384.035808 -85.364828) (xy 384.543808 -85.364828) (xy 384.543808 -84.983828) (xy 384.035808 -84.983828)
				)
			)
		)
		(zone
			(layer "B.Cu")
			(hatch none 0.5)
			(connect_pads
				(clearance 0)
			)
			(min_thickness 0.25)
			(keepout
				(tracks allowed)
				(vias not_allowed)
				(pads allowed)
				(copperpour not_allowed)
				(footprints allowed)
			)
			(placement
				(enabled no)
				(sheetname "")
			)
			(fill
				(thermal_gap 0.5)
				(thermal_bridge_width 0.5)
				(island_removal_mode 0)
			)
			(polygon
				(pts
					(xy 384.035808 -84.983828) (xy 384.543808 -84.983828) (xy 384.543808 -85.364828) (xy 384.035808 -85.364828)
				)
			)
		)
	)
	(footprint ""
		(layer "B.Cu")
		(at 384.725672 -154.721306)
		(property "Reference" "C3L7"
			(at 0 0 0)
			(layer "B.SilkS")
			(hide yes)
			(effects
				(font
					(size 1.27 1.27)
				)
				(justify mirror)
			)
		)
		(property "Value" ""
			(at 0 0 0)
			(layer "B.Fab")
			(effects
				(font
					(size 1.27 1.27)
				)
				(justify mirror)
			)
		)
		(duplicate_pad_numbers_are_jumpers no)
		(fp_poly
			(pts
				(xy 0.7239 -0.2159) (xy -0.7239 -0.2159) (xy -0.7239 1.9939) (xy 0.7239 1.9939)
			)
			(stroke
				(width 0)
				(type default)
			)
			(fill no)
			(layer "B.CrtYd")
		)
		(fp_line
			(start -0.7239 -0.2159)
			(end 0.7239 -0.2159)
			(stroke
				(width 0.1)
				(type default)
			)
			(layer "B.Fab")
		)
		(fp_line
			(start -0.7239 1.9939)
			(end -0.7239 -0.2159)
			(stroke
				(width 0.1)
				(type default)
			)
			(layer "B.Fab")
		)
		(fp_line
			(start 0.7239 -0.2159)
			(end 0.7239 1.9939)
			(stroke
				(width 0.1)
				(type default)
			)
			(layer "B.Fab")
		)
		(fp_line
			(start 0.7239 1.9939)
			(end -0.7239 1.9939)
			(stroke
				(width 0.1)
				(type default)
			)
			(layer "B.Fab")
		)
		(pad "1" smd rect
			(at 0 0 180)
			(size 1.27 1.016)
			(layers "B.Cu" "B.Mask" "B.Paste")
			(net "VR_FET_SW_P12V_STBY_PVDDQ_DEF")
		)
		(pad "2" smd rect
			(at 0 1.778 180)
			(size 1.27 1.016)
			(layers "B.Cu" "B.Mask" "B.Paste")
			(net "GND")
		)
		(zone
			(layer "B.Cu")
			(hatch none 0.5)
			(connect_pads
				(clearance 0)
			)
			(min_thickness 0.25)
			(keepout
				(tracks not_allowed)
				(vias allowed)
				(pads allowed)
				(copperpour not_allowed)
				(footprints allowed)
			)
			(placement
				(enabled no)
				(sheetname "")
			)
			(fill
				(thermal_gap 0.5)
				(thermal_bridge_width 0.5)
				(island_removal_mode 0)
			)
			(polygon
				(pts
					(xy 385.360672 -154.213306) (xy 384.090672 -154.213306) (xy 384.090672 -153.451306) (xy 385.360672 -153.451306)
				)
			)
		)
	)
)
